# S9S_MB_2U (Grand Teton) — schematic netlist excerpt (pin names and nets, part order shuffled) for the footprints in the layout excerpt that follows; sources: Cadence DE-HDL packaged netlist, KiCad conversion of 03242023_DA0F0TMBIJ0_F0T_Motherboard_J_brd_V01_OCP.brd

PC1193_P1_3  Q_CAP  3300PF 50V 10% X7R  pkg 0402  page 290 : A = SW_P12V_PVCCFA_EHV_FIVRA_CPU1_R ; B = GND
PC2241  Q_CAP  0.1UF 25V 10% X7R  pkg 0402  page 242 : A = P12V_SCM_R ; B = GND

(kicad_pcb
	(version 20260206)
	(generator "pcbnew")
	(generator_version "10.0")
	(general
		(thickness 1.6)
		(legacy_teardrops no)
	)
	(paper "A4")
	(title_block
		(title "03242023_DA0F0TMBIJ0_F0T_Motherboard_J_brd_V01_OCP.brd")
		(comment 1 "Grand Teton / footprints 3140-3141 of 6105")
	)
	(layers
		(0 "F.Cu" signal "TOP")
		(4 "In1.Cu" signal "GND")
		(6 "In2.Cu" signal "IN1")
		(8 "In3.Cu" signal "GND1")
		(10 "In4.Cu" signal "IN2")
		(12 "In5.Cu" signal "GND2")
		(14 "In6.Cu" signal "IN3")
		(16 "In7.Cu" signal "GND3")
		(18 "In8.Cu" signal "VCC")
		(20 "In9.Cu" signal "VCC1")
		(22 "In10.Cu" signal "GND4")
		(24 "In11.Cu" signal "IN4")
		(26 "In12.Cu" signal "GND5")
		(28 "In13.Cu" signal "IN5")
		(30 "In14.Cu" signal "GND6")
		(32 "In15.Cu" signal "IN6")
		(34 "In16.Cu" signal "GND7")
		(2 "B.Cu" signal "BOTTOM")
		(9 "F.Adhes" user "F.Adhesive")
		(11 "B.Adhes" user "B.Adhesive")
		(13 "F.Paste" user "Package Geometry/Pastemask Top")
		(15 "B.Paste" user "Package Geometry/Pastemask Bottom")
		(5 "F.SilkS" user "Ref Des/Silkscreen Top")
		(7 "B.SilkS" user "Ref Des/Silkscreen Bottom")
		(1 "F.Mask" user "Board Geometry/Soldermask Top")
		(3 "B.Mask" user "Board Geometry/Soldermask Bottom")
		(17 "Dwgs.User" user "User.Drawings")
		(19 "Cmts.User" user "User.Comments")
		(21 "Eco1.User" user "User.Eco1")
		(23 "Eco2.User" user "User.Eco2")
		(25 "Edge.Cuts" user "Board Geometry/Outline")
		(27 "Margin" user)
		(31 "F.CrtYd" user "Package Geometry/Place Bound Top")
		(29 "B.CrtYd" user "Package Geometry/Place Bound Bottom")
		(35 "F.Fab" user "Ref Des/Assembly Top")
		(33 "B.Fab" user "Ref Des/Assembly Bottom")
	)
	(footprint ""
		(layer "F.Cu")
		(at 186.437524 -353.650296 -90)
		(property "Reference" "PC1193_P1_3"
			(at 0 0 270)
			(layer "F.SilkS")
			(hide yes)
			(effects
				(font
					(size 1.27 1.27)
				)
			)
		)
		(property "Value" ""
			(at 0 0 270)
			(layer "F.Fab")
			(effects
				(font
					(size 1.27 1.27)
				)
			)
		)
		(duplicate_pad_numbers_are_jumpers no)
		(fp_line
			(start -0.7874 0.4064)
			(end -0.7874 -0.4064)
			(stroke
				(width 0.1524)
				(type default)
			)
			(layer "F.SilkS")
		)
		(fp_line
			(start 0.7874 0.4064)
			(end -0.7874 0.4064)
			(stroke
				(width 0.1524)
				(type default)
			)
			(layer "F.SilkS")
		)
		(fp_line
			(start -0.7874 -0.4064)
			(end 0.7874 -0.4064)
			(stroke
				(width 0.1524)
				(type default)
			)
			(layer "F.SilkS")
		)
		(fp_line
			(start 0.7874 -0.4064)
			(end 0.7874 0.4064)
			(stroke
				(width 0.1524)
				(type default)
			)
			(layer "F.SilkS")
		)
		(fp_line
			(start -0.67945 0.3048)
			(end -0.67945 -0.305054)
			(stroke
				(width 0.1)
				(type default)
			)
			(layer "F.Fab")
		)
		(fp_line
			(start -0.12065 0.3048)
			(end -0.67945 0.3048)
			(stroke
				(width 0.1)
				(type default)
			)
			(layer "F.Fab")
		)
		(fp_line
			(start 0.120396 0.3048)
			(end 0.120396 0.2794)
			(stroke
				(width 0.1)
				(type default)
			)
			(layer "F.Fab")
		)
		(fp_line
			(start 0.67945 0.3048)
			(end 0.120396 0.3048)
			(stroke
				(width 0.1)
				(type default)
			)
			(layer "F.Fab")
		)
		(fp_line
			(start -0.12065 0.2794)
			(end -0.12065 0.3048)
			(stroke
				(width 0.1)
				(type default)
			)
			(layer "F.Fab")
		)
		(fp_line
			(start 0.120396 0.2794)
			(end -0.12065 0.2794)
			(stroke
				(width 0.1)
				(type default)
			)
			(layer "F.Fab")
		)
		(fp_line
			(start -0.12065 -0.2794)
			(end 0.12065 -0.2794)
			(stroke
				(width 0.1)
				(type default)
			)
			(layer "F.Fab")
		)
		(fp_line
			(start 0.12065 -0.2794)
			(end 0.12065 -0.3048)
			(stroke
				(width 0.1)
				(type default)
			)
			(layer "F.Fab")
		)
		(fp_line
			(start 0.12065 -0.3048)
			(end 0.67945 -0.3048)
			(stroke
				(width 0.1)
				(type default)
			)
			(layer "F.Fab")
		)
		(fp_line
			(start 0.67945 -0.3048)
			(end 0.67945 0.3048)
			(stroke
				(width 0.1)
				(type default)
			)
			(layer "F.Fab")
		)
		(fp_line
			(start -0.67945 -0.305054)
			(end -0.12065 -0.305054)
			(stroke
				(width 0.1)
				(type default)
			)
			(layer "F.Fab")
		)
		(fp_line
			(start -0.12065 -0.305054)
			(end -0.12065 -0.2794)
			(stroke
				(width 0.1)
				(type default)
			)
			(layer "F.Fab")
		)
		(pad "1" smd circle
			(at -0.40005 0 270)
			(size 0 0)
			(layers "F.Cu" "F.Mask" "F.Paste")
			(net "SW_P12V_PVCCFA_EHV_FIVRA_CPU1_R")
		)
		(pad "2" smd circle
			(at 0.40005 0 270)
			(size 0 0)
			(layers "F.Cu" "F.Mask" "F.Paste")
			(net "GND")
		)
	)
	(footprint ""
		(layer "F.Cu")
		(at 179.939442 -26.240232)
		(property "Reference" "PC2241"
			(at 0 0 0)
			(layer "F.SilkS")
			(hide yes)
			(effects
				(font
					(size 1.27 1.27)
				)
			)
		)
		(property "Value" ""
			(at 0 0 0)
			(layer "F.Fab")
			(effects
				(font
					(size 1.27 1.27)
				)
			)
		)
		(duplicate_pad_numbers_are_jumpers no)
		(fp_line
			(start -0.7874 -0.4064)
			(end 0.7874 -0.4064)
			(stroke
				(width 0.1524)
				(type default)
			)
			(layer "F.SilkS")
		)
		(fp_line
			(start -0.7874 0.4064)
			(end -0.7874 -0.4064)
			(stroke
				(width 0.1524)
				(type default)
			)
			(layer "F.SilkS")
		)
		(fp_line
			(start 0.7874 -0.4064)
			(end 0.7874 0.4064)
			(stroke
				(width 0.1524)
				(type default)
			)
			(layer "F.SilkS")
		)
		(fp_line
			(start 0.7874 0.4064)
			(end -0.7874 0.4064)
			(stroke
				(width 0.1524)
				(type default)
			)
			(layer "F.SilkS")
		)
		(fp_line
			(start -0.67945 -0.305054)
			(end -0.12065 -0.305054)
			(stroke
				(width 0.1)
				(type default)
			)
			(layer "F.Fab")
		)
		(fp_line
			(start -0.67945 0.3048)
			(end -0.67945 -0.305054)
			(stroke
				(width 0.1)
				(type default)
			)
			(layer "F.Fab")
		)
		(fp_line
			(start -0.12065 -0.305054)
			(end -0.12065 -0.2794)
			(stroke
				(width 0.1)
				(type default)
			)
			(layer "F.Fab")
		)
		(fp_line
			(start -0.12065 -0.2794)
			(end 0.12065 -0.2794)
			(stroke
				(width 0.1)
				(type default)
			)
			(layer "F.Fab")
		)
		(fp_line
			(start -0.12065 0.2794)
			(end -0.12065 0.3048)
			(stroke
				(width 0.1)
				(type default)
			)
			(layer "F.Fab")
		)
		(fp_line
			(start -0.12065 0.3048)
			(end -0.67945 0.3048)
			(stroke
				(width 0.1)
				(type default)
			)
			(layer "F.Fab")
		)
		(fp_line
			(start 0.120396 0.2794)
			(end -0.12065 0.2794)
			(stroke
				(width 0.1)
				(type default)
			)
			(layer "F.Fab")
		)
		(fp_line
			(start 0.120396 0.3048)
			(end 0.120396 0.2794)
			(stroke
				(width 0.1)
				(type default)
			)
			(layer "F.Fab")
		)
		(fp_line
			(start 0.12065 -0.3048)
			(end 0.67945 -0.3048)
			(stroke
				(width 0.1)
				(type default)
			)
			(layer "F.Fab")
		)
		(fp_line
			(start 0.12065 -0.2794)
			(end 0.12065 -0.3048)
			(stroke
				(width 0.1)
				(type default)
			)
			(layer "F.Fab")
		)
		(fp_line
			(start 0.67945 -0.3048)
			(end 0.67945 0.3048)
			(stroke
				(width 0.1)
				(type default)
			)
			(layer "F.Fab")
		)
		(fp_line
			(start 0.67945 0.3048)
			(end 0.120396 0.3048)
			(stroke
				(width 0.1)
				(type default)
			)
			(layer "F.Fab")
		)
		(pad "1" smd circle
			(at -0.40005 0)
			(size 0 0)
			(layers "F.Cu" "F.Mask" "F.Paste")
			(net "P12V_SCM_R")
		)
		(pad "2" smd circle
			(at 0.40005 0)
			(size 0 0)
			(layers "F.Cu" "F.Mask" "F.Paste")
			(net "GND")
		)
	)
)
